(kicad_pcb
	(version 20260206)
	(generator "pcbnew")
	(generator_version "10.0")
	(general
		(thickness 1.6)
		(legacy_teardrops no)
	)
	(paper "A4")
	(title_block
		(title "12092022_DA0F0TFB6D0_F0T_FAN_BOARD_MP5048_D_brd_v02_OCP.brd")
		(comment 1 "Grand Teton / footprints 7-7 of 924")
	)
	(layers
		(0 "F.Cu" signal "TOP")
		(4 "In1.Cu" signal "GND")
		(6 "In2.Cu" signal "IN1")
		(8 "In3.Cu" signal "IN2")
		(10 "In4.Cu" signal "GND1")
		(2 "B.Cu" signal "BOTTOM")
		(9 "F.Adhes" user "F.Adhesive")
		(11 "B.Adhes" user "B.Adhesive")
		(13 "F.Paste" user "Package Geometry/Pastemask Top")
		(15 "B.Paste" user "Package Geometry/Pastemask Bottom")
		(5 "F.SilkS" user "Ref Des/Silkscreen Top")
		(7 "B.SilkS" user "Ref Des/Silkscreen Bottom")
		(1 "F.Mask" user "Board Geometry/Soldermask Top")
		(3 "B.Mask" user "Board Geometry/Soldermask Bottom")
		(17 "Dwgs.User" user "User.Drawings")
		(19 "Cmts.User" user "User.Comments")
		(21 "Eco1.User" user "User.Eco1")
		(23 "Eco2.User" user "User.Eco2")
		(25 "Edge.Cuts" user "Board Geometry/Outline")
		(27 "Margin" user)
		(31 "F.CrtYd" user "Package Geometry/Place Bound Top")
		(29 "B.CrtYd" user "Package Geometry/Place Bound Bottom")
		(35 "F.Fab" user "Ref Des/Assembly Top")
		(33 "B.Fab" user "Ref Des/Assembly Bottom")
	)
	(footprint ""
		(layer "F.Cu")
		(at 18.756122 -30.353 180)
		(property "Reference" "R5309"
			(at 0 0 180)
			(layer "F.SilkS")
			(hide yes)
			(effects
				(font
					(size 1.27 1.27)
				)
			)
		)
		(property "Value" ""
			(at 0 0 180)
			(layer "F.Fab")
			(effects
				(font
					(size 1.27 1.27)
				)
			)
		)
		(duplicate_pad_numbers_are_jumpers no)
		(fp_line
			(start 1.2954 0.5842)
			(end -1.2954 0.5842)
			(stroke
				(width 0.1524)
				(type default)
			)
			(layer "F.SilkS")
		)
		(fp_line
			(start 1.2954 -0.5842)
			(end 1.2954 0.5842)
			(stroke
				(width 0.1524)
				(type default)
			)
			(layer "F.SilkS")
		)
		(fp_line
			(start -1.2954 0.5842)
			(end -1.2954 -0.5842)
			(stroke
				(width 0.1524)
				(type default)
			)
			(layer "F.SilkS")
		)
		(fp_line
			(start -1.2954 -0.5842)
			(end 1.2954 -0.5842)
			(stroke
				(width 0.1524)
				(type default)
			)
			(layer "F.SilkS")
		)
		(fp_line
			(start 1.1938 0.4064)
			(end 0.8636 0.4064)
			(stroke
				(width 0.1)
				(type default)
			)
			(layer "F.Fab")
		)
		(fp_line
			(start 1.1938 -0.406654)
			(end 1.1938 0.4064)
			(stroke
				(width 0.1)
				(type default)
			)
			(layer "F.Fab")
		)
		(fp_line
			(start 0.8636 0.4572)
			(end -0.8636 0.4572)
			(stroke
				(width 0.1)
				(type default)
			)
			(layer "F.Fab")
		)
		(fp_line
			(start 0.8636 0.4064)
			(end 0.8636 0.4572)
			(stroke
				(width 0.1)
				(type default)
			)
			(layer "F.Fab")
		)
		(fp_line
			(start 0.8636 -0.406654)
			(end 1.1938 -0.406654)
			(stroke
				(width 0.1)
				(type default)
			)
			(layer "F.Fab")
		)
		(fp_line
			(start 0.8636 -0.4572)
			(end 0.8636 -0.406654)
			(stroke
				(width 0.1)
				(type default)
			)
			(layer "F.Fab")
		)
		(fp_line
			(start -0.8636 0.4572)
			(end -0.8636 0.4318)
			(stroke
				(width 0.1)
				(type default)
			)
			(layer "F.Fab")
		)
		(fp_line
			(start -0.8636 0.4318)
			(end -0.8636 0.4064)
			(stroke
				(width 0.1)
				(type default)
			)
			(layer "F.Fab")
		)
		(fp_line
			(start -0.8636 0.4064)
			(end -1.1938 0.4064)
			(stroke
				(width 0.1)
				(type default)
			)
			(layer "F.Fab")
		)
		(fp_line
			(start -0.8636 -0.406654)
			(end -0.8636 -0.4572)
			(stroke
				(width 0.1)
				(type default)
			)
			(layer "F.Fab")
		)
		(fp_line
			(start -0.8636 -0.4572)
			(end 0.8636 -0.4572)
			(stroke
				(width 0.1)
				(type default)
			)
			(layer "F.Fab")
		)
		(fp_line
			(start -1.1938 0.4064)
			(end -1.1938 -0.406654)
			(stroke
				(width 0.1)
				(type default)
			)
			(layer "F.Fab")
		)
		(fp_line
			(start -1.1938 -0.406654)
			(end -0.8636 -0.406654)
			(stroke
				(width 0.1)
				(type default)
			)
			(layer "F.Fab")
		)
		(pad "1" smd rect
			(at -0.7366 0 90)
			(size 0.7112 0.8128)
			(layers "F.Cu" "F.Mask" "F.Paste")
			(net "P52V_FAN_4")
		)
		(pad "2" smd rect
			(at 0.7366 0 90)
			(size 0.7112 0.8128)
			(layers "F.Cu" "F.Mask" "F.Paste")
			(net "FAN_4_TACH_OL_R")
		)
	)
)
